(kicad_pcb
	(version 20260206)
	(generator "pcbnew")
	(generator_version "10.0")
	(general
		(thickness 1.6)
		(legacy_teardrops no)
	)
	(paper "A4")
	(title_block
		(title "03242023_DA0F0TMBIJ0_F0T_Motherboard_J_brd_V01_OCP.brd")
		(comment 1 "Grand Teton / footprints 4963-4969 of 6105")
	)
	(layers
		(0 "F.Cu" signal "TOP")
		(4 "In1.Cu" signal "GND")
		(6 "In2.Cu" signal "IN1")
		(8 "In3.Cu" signal "GND1")
		(10 "In4.Cu" signal "IN2")
		(12 "In5.Cu" signal "GND2")
		(14 "In6.Cu" signal "IN3")
		(16 "In7.Cu" signal "GND3")
		(18 "In8.Cu" signal "VCC")
		(20 "In9.Cu" signal "VCC1")
		(22 "In10.Cu" signal "GND4")
		(24 "In11.Cu" signal "IN4")
		(26 "In12.Cu" signal "GND5")
		(28 "In13.Cu" signal "IN5")
		(30 "In14.Cu" signal "GND6")
		(32 "In15.Cu" signal "IN6")
		(34 "In16.Cu" signal "GND7")
		(2 "B.Cu" signal "BOTTOM")
		(9 "F.Adhes" user "F.Adhesive")
		(11 "B.Adhes" user "B.Adhesive")
		(13 "F.Paste" user "Package Geometry/Pastemask Top")
		(15 "B.Paste" user "Package Geometry/Pastemask Bottom")
		(5 "F.SilkS" user "Ref Des/Silkscreen Top")
		(7 "B.SilkS" user "Ref Des/Silkscreen Bottom")
		(1 "F.Mask" user "Board Geometry/Soldermask Top")
		(3 "B.Mask" user "Board Geometry/Soldermask Bottom")
		(17 "Dwgs.User" user "User.Drawings")
		(19 "Cmts.User" user "User.Comments")
		(21 "Eco1.User" user "User.Eco1")
		(23 "Eco2.User" user "User.Eco2")
		(25 "Edge.Cuts" user "Board Geometry/Outline")
		(27 "Margin" user)
		(31 "F.CrtYd" user "Package Geometry/Place Bound Top")
		(29 "B.CrtYd" user "Package Geometry/Place Bound Bottom")
		(35 "F.Fab" user "Ref Des/Assembly Top")
		(33 "B.Fab" user "Ref Des/Assembly Bottom")
	)
	(footprint ""
		(layer "B.Cu")
		(at 169.389806 -9.458198 -90)
		(property "Reference" "C2077"
			(at 0 0 90)
			(layer "B.SilkS")
			(hide yes)
			(effects
				(font
					(size 1.27 1.27)
				)
				(justify mirror)
			)
		)
		(property "Value" ""
			(at 0 0 90)
			(layer "B.Fab")
			(effects
				(font
					(size 1.27 1.27)
				)
				(justify mirror)
			)
		)
		(duplicate_pad_numbers_are_jumpers no)
		(fp_line
			(start -0.299974 0.150114)
			(end 0.299974 0.150114)
			(stroke
				(width 0.1)
				(type default)
			)
			(layer "B.Fab")
		)
		(fp_line
			(start 0.299974 0.150114)
			(end 0.299974 -0.150114)
			(stroke
				(width 0.1)
				(type default)
			)
			(layer "B.Fab")
		)
		(fp_line
			(start -0.299974 -0.150114)
			(end -0.299974 0.150114)
			(stroke
				(width 0.1)
				(type default)
			)
			(layer "B.Fab")
		)
		(fp_line
			(start 0.299974 -0.150114)
			(end -0.299974 -0.150114)
			(stroke
				(width 0.1)
				(type default)
			)
			(layer "B.Fab")
		)
		(pad "1" smd rect
			(at 0.2667 0 90)
			(size 0.3048 0.381)
			(layers "B.Cu" "B.Mask" "B.Paste")
			(net "P3E_PCH_BMC_TX_DP")
		)
		(pad "2" smd rect
			(at -0.2667 0 90)
			(size 0.3048 0.381)
			(layers "B.Cu" "B.Mask" "B.Paste")
			(net "P3E_PCH_BMC_TX_C_DP")
		)
		(zone
			(layer "In16.Cu")
			(hatch none 0.5)
			(connect_pads
				(clearance 0)
			)
			(min_thickness 0.25)
			(keepout
				(tracks not_allowed)
				(vias allowed)
				(pads allowed)
				(copperpour not_allowed)
				(footprints allowed)
			)
			(placement
				(enabled no)
				(sheetname "")
			)
			(fill
				(thermal_gap 0.5)
				(thermal_bridge_width 0.5)
				(island_removal_mode 0)
			)
			(polygon
				(pts
					(xy 169.148506 -9.521698) (xy 169.631106 -9.521698) (xy 169.631106 -9.928098) (xy 169.148506 -9.928098)
				)
			)
		)
		(zone
			(layer "In16.Cu")
			(hatch none 0.5)
			(connect_pads
				(clearance 0)
			)
			(min_thickness 0.25)
			(keepout
				(tracks not_allowed)
				(vias allowed)
				(pads allowed)
				(copperpour not_allowed)
				(footprints allowed)
			)
			(placement
				(enabled no)
				(sheetname "")
			)
			(fill
				(thermal_gap 0.5)
				(thermal_bridge_width 0.5)
				(island_removal_mode 0)
			)
			(polygon
				(pts
					(xy 169.148506 -8.988298) (xy 169.631106 -8.988298) (xy 169.631106 -9.394698) (xy 169.148506 -9.394698)
				)
			)
		)
	)
	(footprint ""
		(layer "B.Cu")
		(at 339.44306 -66.425064 90)
		(property "Reference" "C168"
			(at 0 0 90)
			(layer "B.SilkS")
			(hide yes)
			(effects
				(font
					(size 1.27 1.27)
				)
				(justify mirror)
			)
		)
		(property "Value" ""
			(at 0 0 90)
			(layer "B.Fab")
			(effects
				(font
					(size 1.27 1.27)
				)
				(justify mirror)
			)
		)
		(duplicate_pad_numbers_are_jumpers no)
		(fp_line
			(start 0.299974 -0.150114)
			(end -0.299974 -0.150114)
			(stroke
				(width 0.1)
				(type default)
			)
			(layer "B.Fab")
		)
		(fp_line
			(start -0.299974 -0.150114)
			(end -0.299974 0.150114)
			(stroke
				(width 0.1)
				(type default)
			)
			(layer "B.Fab")
		)
		(fp_line
			(start 0.299974 0.150114)
			(end 0.299974 -0.150114)
			(stroke
				(width 0.1)
				(type default)
			)
			(layer "B.Fab")
		)
		(fp_line
			(start -0.299974 0.150114)
			(end 0.299974 0.150114)
			(stroke
				(width 0.1)
				(type default)
			)
			(layer "B.Fab")
		)
		(pad "1" smd rect
			(at 0.2667 0 270)
			(size 0.3048 0.381)
			(layers "B.Cu" "B.Mask" "B.Paste")
			(net "DMI_CPU0_PCH_RX_C_DP<1>")
		)
		(pad "2" smd rect
			(at -0.2667 0 270)
			(size 0.3048 0.381)
			(layers "B.Cu" "B.Mask" "B.Paste")
			(net "DMI_CPU0_PCH_RX_DP<1>")
		)
	)
	(footprint ""
		(layer "B.Cu")
		(at 185.240422 -13.60043 -90)
		(property "Reference" "R598"
			(at 0 0 90)
			(layer "B.SilkS")
			(hide yes)
			(effects
				(font
					(size 1.27 1.27)
				)
				(justify mirror)
			)
		)
		(property "Value" ""
			(at 0 0 90)
			(layer "B.Fab")
			(effects
				(font
					(size 1.27 1.27)
				)
				(justify mirror)
			)
		)
		(duplicate_pad_numbers_are_jumpers no)
		(fp_line
			(start -0.7874 0.4064)
			(end 0.7874 0.4064)
			(stroke
				(width 0.1524)
				(type default)
			)
			(layer "B.SilkS")
		)
		(fp_line
			(start 0.7874 0.4064)
			(end 0.7874 -0.4064)
			(stroke
				(width 0.1524)
				(type default)
			)
			(layer "B.SilkS")
		)
		(fp_line
			(start -0.7874 -0.4064)
			(end -0.7874 0.4064)
			(stroke
				(width 0.1524)
				(type default)
			)
			(layer "B.SilkS")
		)
		(fp_line
			(start 0.7874 -0.4064)
			(end -0.7874 -0.4064)
			(stroke
				(width 0.1524)
				(type default)
			)
			(layer "B.SilkS")
		)
		(fp_line
			(start -0.67945 0.3048)
			(end -0.120396 0.3048)
			(stroke
				(width 0.1)
				(type default)
			)
			(layer "B.Fab")
		)
		(fp_line
			(start -0.120396 0.3048)
			(end -0.120396 0.2794)
			(stroke
				(width 0.1)
				(type default)
			)
			(layer "B.Fab")
		)
		(fp_line
			(start 0.12065 0.3048)
			(end 0.67945 0.3048)
			(stroke
				(width 0.1)
				(type default)
			)
			(layer "B.Fab")
		)
		(fp_line
			(start 0.67945 0.3048)
			(end 0.67945 -0.305054)
			(stroke
				(width 0.1)
				(type default)
			)
			(layer "B.Fab")
		)
		(fp_line
			(start -0.120396 0.2794)
			(end 0.12065 0.2794)
			(stroke
				(width 0.1)
				(type default)
			)
			(layer "B.Fab")
		)
		(fp_line
			(start 0.12065 0.2794)
			(end 0.12065 0.3048)
			(stroke
				(width 0.1)
				(type default)
			)
			(layer "B.Fab")
		)
		(fp_line
			(start -0.12065 -0.2794)
			(end -0.12065 -0.3048)
			(stroke
				(width 0.1)
				(type default)
			)
			(layer "B.Fab")
		)
		(fp_line
			(start 0.12065 -0.2794)
			(end -0.12065 -0.2794)
			(stroke
				(width 0.1)
				(type default)
			)
			(layer "B.Fab")
		)
		(fp_line
			(start -0.67945 -0.3048)
			(end -0.67945 0.3048)
			(stroke
				(width 0.1)
				(type default)
			)
			(layer "B.Fab")
		)
		(fp_line
			(start -0.12065 -0.3048)
			(end -0.67945 -0.3048)
			(stroke
				(width 0.1)
				(type default)
			)
			(layer "B.Fab")
		)
		(fp_line
			(start 0.12065 -0.305054)
			(end 0.12065 -0.2794)
			(stroke
				(width 0.1)
				(type default)
			)
			(layer "B.Fab")
		)
		(fp_line
			(start 0.67945 -0.305054)
			(end 0.12065 -0.305054)
			(stroke
				(width 0.1)
				(type default)
			)
			(layer "B.Fab")
		)
		(pad "1" smd circle
			(at 0.40005 0 90)
			(size 0 0)
			(layers "B.Cu" "B.Mask" "B.Paste")
			(net "I3C_SPD_DDRABCD_CPU1_BMC_R_SDA")
		)
		(pad "2" smd circle
			(at -0.40005 0 90)
			(size 0 0)
			(layers "B.Cu" "B.Mask" "B.Paste")
			(net "I3C_SPD_DDRABCD_CPU1_BMC_SDA")
		)
	)
	(footprint ""
		(layer "B.Cu")
		(at 359.24998 -212.049614)
		(property "Reference" "C499"
			(at 0 0 0)
			(layer "B.SilkS")
			(hide yes)
			(effects
				(font
					(size 1.27 1.27)
				)
				(justify mirror)
			)
		)
		(property "Value" ""
			(at 0 0 0)
			(layer "B.Fab")
			(effects
				(font
					(size 1.27 1.27)
				)
				(justify mirror)
			)
		)
		(duplicate_pad_numbers_are_jumpers no)
		(fp_line
			(start -1.524 -0.762)
			(end -1.524 0.762)
			(stroke
				(width 0.1524)
				(type default)
			)
			(layer "B.SilkS")
		)
		(fp_line
			(start -1.524 0.762)
			(end 1.524 0.762)
			(stroke
				(width 0.1524)
				(type default)
			)
			(layer "B.SilkS")
		)
		(fp_line
			(start 1.524 -0.762)
			(end -1.524 -0.762)
			(stroke
				(width 0.1524)
				(type default)
			)
			(layer "B.SilkS")
		)
		(fp_line
			(start 1.524 0.762)
			(end 1.524 -0.762)
			(stroke
				(width 0.1524)
				(type default)
			)
			(layer "B.SilkS")
		)
		(fp_line
			(start -1.1049 -0.724916)
			(end 1.1049 -0.724916)
			(stroke
				(width 0.1)
				(type default)
			)
			(layer "B.Fab")
		)
		(fp_line
			(start -1.1049 0.724916)
			(end -1.1049 -0.724916)
			(stroke
				(width 0.1)
				(type default)
			)
			(layer "B.Fab")
		)
		(fp_line
			(start 1.1049 -0.724916)
			(end 1.1049 0.724916)
			(stroke
				(width 0.1)
				(type default)
			)
			(layer "B.Fab")
		)
		(fp_line
			(start 1.1049 0.724916)
			(end -1.1049 0.724916)
			(stroke
				(width 0.1)
				(type default)
			)
			(layer "B.Fab")
		)
		(pad "1" smd rect
			(at 0.889 0)
			(size 1.016 1.27)
			(layers "B.Cu" "B.Mask" "B.Paste")
			(net "PVCCD_HV_CPU0")
		)
		(pad "2" smd rect
			(at -0.889 0)
			(size 1.016 1.27)
			(layers "B.Cu" "B.Mask" "B.Paste")
			(net "GND")
		)
	)
	(footprint ""
		(layer "B.Cu")
		(at 136.60755 -28.598368)
		(property "Reference" "C2325"
			(at 0 0 0)
			(layer "B.SilkS")
			(hide yes)
			(effects
				(font
					(size 1.27 1.27)
				)
				(justify mirror)
			)
		)
		(property "Value" ""
			(at 0 0 0)
			(layer "B.Fab")
			(effects
				(font
					(size 1.27 1.27)
				)
				(justify mirror)
			)
		)
		(duplicate_pad_numbers_are_jumpers no)
		(fp_line
			(start -0.7874 -0.4064)
			(end -0.7874 0.4064)
			(stroke
				(width 0.1524)
				(type default)
			)
			(layer "B.SilkS")
		)
		(fp_line
			(start -0.7874 0.4064)
			(end 0.7874 0.4064)
			(stroke
				(width 0.1524)
				(type default)
			)
			(layer "B.SilkS")
		)
		(fp_line
			(start 0.7874 -0.4064)
			(end -0.7874 -0.4064)
			(stroke
				(width 0.1524)
				(type default)
			)
			(layer "B.SilkS")
		)
		(fp_line
			(start 0.7874 0.4064)
			(end 0.7874 -0.4064)
			(stroke
				(width 0.1524)
				(type default)
			)
			(layer "B.SilkS")
		)
		(fp_line
			(start -0.67945 -0.3048)
			(end -0.67945 0.3048)
			(stroke
				(width 0.1)
				(type default)
			)
			(layer "B.Fab")
		)
		(fp_line
			(start -0.67945 0.3048)
			(end -0.120396 0.3048)
			(stroke
				(width 0.1)
				(type default)
			)
			(layer "B.Fab")
		)
		(fp_line
			(start -0.12065 -0.3048)
			(end -0.67945 -0.3048)
			(stroke
				(width 0.1)
				(type default)
			)
			(layer "B.Fab")
		)
		(fp_line
			(start -0.12065 -0.2794)
			(end -0.12065 -0.3048)
			(stroke
				(width 0.1)
				(type default)
			)
			(layer "B.Fab")
		)
		(fp_line
			(start -0.120396 0.2794)
			(end 0.12065 0.2794)
			(stroke
				(width 0.1)
				(type default)
			)
			(layer "B.Fab")
		)
		(fp_line
			(start -0.120396 0.3048)
			(end -0.120396 0.2794)
			(stroke
				(width 0.1)
				(type default)
			)
			(layer "B.Fab")
		)
		(fp_line
			(start 0.12065 -0.305054)
			(end 0.12065 -0.2794)
			(stroke
				(width 0.1)
				(type default)
			)
			(layer "B.Fab")
		)
		(fp_line
			(start 0.12065 -0.2794)
			(end -0.12065 -0.2794)
			(stroke
				(width 0.1)
				(type default)
			)
			(layer "B.Fab")
		)
		(fp_line
			(start 0.12065 0.2794)
			(end 0.12065 0.3048)
			(stroke
				(width 0.1)
				(type default)
			)
			(layer "B.Fab")
		)
		(fp_line
			(start 0.12065 0.3048)
			(end 0.67945 0.3048)
			(stroke
				(width 0.1)
				(type default)
			)
			(layer "B.Fab")
		)
		(fp_line
			(start 0.67945 -0.305054)
			(end 0.12065 -0.305054)
			(stroke
				(width 0.1)
				(type default)
			)
			(layer "B.Fab")
		)
		(fp_line
			(start 0.67945 0.3048)
			(end 0.67945 -0.305054)
			(stroke
				(width 0.1)
				(type default)
			)
			(layer "B.Fab")
		)
		(pad "1" smd circle
			(at 0.40005 0 180)
			(size 0 0)
			(layers "B.Cu" "B.Mask" "B.Paste")
			(net "PD_USB_HUB_2_VREG")
		)
		(pad "2" smd circle
			(at -0.40005 0 180)
			(size 0 0)
			(layers "B.Cu" "B.Mask" "B.Paste")
			(net "GND")
		)
	)
	(footprint ""
		(layer "B.Cu")
		(at 154.21102 -226.406456 180)
		(property "Reference" "R961"
			(at 0 0 0)
			(layer "B.SilkS")
			(hide yes)
			(effects
				(font
					(size 1.27 1.27)
				)
				(justify mirror)
			)
		)
		(property "Value" ""
			(at 0 0 0)
			(layer "B.Fab")
			(effects
				(font
					(size 1.27 1.27)
				)
				(justify mirror)
			)
		)
		(duplicate_pad_numbers_are_jumpers no)
		(fp_line
			(start 0.7874 0.4064)
			(end 0.7874 -0.4064)
			(stroke
				(width 0.1524)
				(type default)
			)
			(layer "B.SilkS")
		)
		(fp_line
			(start 0.7874 -0.4064)
			(end -0.7874 -0.4064)
			(stroke
				(width 0.1524)
				(type default)
			)
			(layer "B.SilkS")
		)
		(fp_line
			(start -0.7874 0.4064)
			(end 0.7874 0.4064)
			(stroke
				(width 0.1524)
				(type default)
			)
			(layer "B.SilkS")
		)
		(fp_line
			(start -0.7874 -0.4064)
			(end -0.7874 0.4064)
			(stroke
				(width 0.1524)
				(type default)
			)
			(layer "B.SilkS")
		)
		(fp_line
			(start 0.67945 0.3048)
			(end 0.67945 -0.305054)
			(stroke
				(width 0.1)
				(type default)
			)
			(layer "B.Fab")
		)
		(fp_line
			(start 0.67945 -0.305054)
			(end 0.12065 -0.305054)
			(stroke
				(width 0.1)
				(type default)
			)
			(layer "B.Fab")
		)
		(fp_line
			(start 0.12065 0.3048)
			(end 0.67945 0.3048)
			(stroke
				(width 0.1)
				(type default)
			)
			(layer "B.Fab")
		)
		(fp_line
			(start 0.12065 0.2794)
			(end 0.12065 0.3048)
			(stroke
				(width 0.1)
				(type default)
			)
			(layer "B.Fab")
		)
		(fp_line
			(start 0.12065 -0.2794)
			(end -0.12065 -0.2794)
			(stroke
				(width 0.1)
				(type default)
			)
			(layer "B.Fab")
		)
		(fp_line
			(start 0.12065 -0.305054)
			(end 0.12065 -0.2794)
			(stroke
				(width 0.1)
				(type default)
			)
			(layer "B.Fab")
		)
		(fp_line
			(start -0.120396 0.3048)
			(end -0.120396 0.2794)
			(stroke
				(width 0.1)
				(type default)
			)
			(layer "B.Fab")
		)
		(fp_line
			(start -0.120396 0.2794)
			(end 0.12065 0.2794)
			(stroke
				(width 0.1)
				(type default)
			)
			(layer "B.Fab")
		)
		(fp_line
			(start -0.12065 -0.2794)
			(end -0.12065 -0.3048)
			(stroke
				(width 0.1)
				(type default)
			)
			(layer "B.Fab")
		)
		(fp_line
			(start -0.12065 -0.3048)
			(end -0.67945 -0.3048)
			(stroke
				(width 0.1)
				(type default)
			)
			(layer "B.Fab")
		)
		(fp_line
			(start -0.67945 0.3048)
			(end -0.120396 0.3048)
			(stroke
				(width 0.1)
				(type default)
			)
			(layer "B.Fab")
		)
		(fp_line
			(start -0.67945 -0.3048)
			(end -0.67945 0.3048)
			(stroke
				(width 0.1)
				(type default)
			)
			(layer "B.Fab")
		)
		(pad "1" smd circle
			(at 0.40005 0)
			(size 0 0)
			(layers "B.Cu" "B.Mask" "B.Paste")
			(net "SMB_PEHPCPU1_GTL_SCL")
		)
		(pad "2" smd circle
			(at -0.40005 0)
			(size 0 0)
			(layers "B.Cu" "B.Mask" "B.Paste")
			(net "SMB_PEHPCPU1_GTL_R_SCL")
		)
	)
	(footprint ""
		(layer "B.Cu")
		(at 362.7374 -183.373776 180)
		(property "Reference" "R998"
			(at 0 0 0)
			(layer "B.SilkS")
			(hide yes)
			(effects
				(font
					(size 1.27 1.27)
				)
				(justify mirror)
			)
		)
		(property "Value" ""
			(at 0 0 0)
			(layer "B.Fab")
			(effects
				(font
					(size 1.27 1.27)
				)
				(justify mirror)
			)
		)
		(duplicate_pad_numbers_are_jumpers no)
		(fp_line
			(start 0.7874 0.4064)
			(end 0.7874 -0.4064)
			(stroke
				(width 0.1524)
				(type default)
			)
			(layer "B.SilkS")
		)
		(fp_line
			(start 0.7874 -0.4064)
			(end -0.7874 -0.4064)
			(stroke
				(width 0.1524)
				(type default)
			)
			(layer "B.SilkS")
		)
		(fp_line
			(start -0.7874 0.4064)
			(end 0.7874 0.4064)
			(stroke
				(width 0.1524)
				(type default)
			)
			(layer "B.SilkS")
		)
		(fp_line
			(start -0.7874 -0.4064)
			(end -0.7874 0.4064)
			(stroke
				(width 0.1524)
				(type default)
			)
			(layer "B.SilkS")
		)
		(fp_line
			(start 0.67945 0.3048)
			(end 0.67945 -0.305054)
			(stroke
				(width 0.1)
				(type default)
			)
			(layer "B.Fab")
		)
		(fp_line
			(start 0.67945 -0.305054)
			(end 0.12065 -0.305054)
			(stroke
				(width 0.1)
				(type default)
			)
			(layer "B.Fab")
		)
		(fp_line
			(start 0.12065 0.3048)
			(end 0.67945 0.3048)
			(stroke
				(width 0.1)
				(type default)
			)
			(layer "B.Fab")
		)
		(fp_line
			(start 0.12065 0.2794)
			(end 0.12065 0.3048)
			(stroke
				(width 0.1)
				(type default)
			)
			(layer "B.Fab")
		)
		(fp_line
			(start 0.12065 -0.2794)
			(end -0.12065 -0.2794)
			(stroke
				(width 0.1)
				(type default)
			)
			(layer "B.Fab")
		)
		(fp_line
			(start 0.12065 -0.305054)
			(end 0.12065 -0.2794)
			(stroke
				(width 0.1)
				(type default)
			)
			(layer "B.Fab")
		)
		(fp_line
			(start -0.120396 0.3048)
			(end -0.120396 0.2794)
			(stroke
				(width 0.1)
				(type default)
			)
			(layer "B.Fab")
		)
		(fp_line
			(start -0.120396 0.2794)
			(end 0.12065 0.2794)
			(stroke
				(width 0.1)
				(type default)
			)
			(layer "B.Fab")
		)
		(fp_line
			(start -0.12065 -0.2794)
			(end -0.12065 -0.3048)
			(stroke
				(width 0.1)
				(type default)
			)
			(layer "B.Fab")
		)
		(fp_line
			(start -0.12065 -0.3048)
			(end -0.67945 -0.3048)
			(stroke
				(width 0.1)
				(type default)
			)
			(layer "B.Fab")
		)
		(fp_line
			(start -0.67945 0.3048)
			(end -0.120396 0.3048)
			(stroke
				(width 0.1)
				(type default)
			)
			(layer "B.Fab")
		)
		(fp_line
			(start -0.67945 -0.3048)
			(end -0.67945 0.3048)
			(stroke
				(width 0.1)
				(type default)
			)
			(layer "B.Fab")
		)
		(pad "1" smd circle
			(at 0.40005 0)
			(size 0 0)
			(layers "B.Cu" "B.Mask" "B.Paste")
			(net "FM_SMB_PEHPCPU0_PCIE_ALERT_N")
		)
		(pad "2" smd circle
			(at -0.40005 0)
			(size 0 0)
			(layers "B.Cu" "B.Mask" "B.Paste")
			(net "FM_SMB_PEHPCPU0_PCIE_ALERT_R_N")
		)
	)
)
